(kicad_pcb
	(version 20260206)
	(generator "pcbnew")
	(generator_version "10.0")
	(general
		(thickness 1.6)
		(legacy_teardrops no)
	)
	(paper "A4")
	(title_block
		(title "Wiwynn_Tioga_Pass_MB.brd")
		(comment 1 "Tioga Pass / footprints 1404-1410 of 4770")
	)
	(layers
		(0 "F.Cu" signal "TOP")
		(4 "In1.Cu" signal "L2GND")
		(6 "In2.Cu" signal "L3")
		(8 "In3.Cu" signal "L4GND")
		(10 "In4.Cu" signal "L5")
		(12 "In5.Cu" signal "L6GND")
		(14 "In6.Cu" signal "L7VCC")
		(16 "In7.Cu" signal "L8VCC")
		(18 "In8.Cu" signal "L9GND")
		(20 "In9.Cu" signal "L10")
		(22 "In10.Cu" signal "L11GND")
		(24 "In11.Cu" signal "L12")
		(26 "In12.Cu" signal "L13GND")
		(2 "B.Cu" signal "BOTTOM")
		(9 "F.Adhes" user "F.Adhesive")
		(11 "B.Adhes" user "B.Adhesive")
		(13 "F.Paste" user "Package Geometry/Pastemask Top")
		(15 "B.Paste" user "Package Geometry/Pastemask Bottom")
		(5 "F.SilkS" user "Ref Des/Silkscreen Top")
		(7 "B.SilkS" user "Ref Des/Silkscreen Bottom")
		(1 "F.Mask" user "Board Geometry/Soldermask Top")
		(3 "B.Mask" user "Board Geometry/Soldermask Bottom")
		(17 "Dwgs.User" user "User.Drawings")
		(19 "Cmts.User" user "User.Comments")
		(21 "Eco1.User" user "User.Eco1")
		(23 "Eco2.User" user "User.Eco2")
		(25 "Edge.Cuts" user "Board Geometry/Outline")
		(27 "Margin" user)
		(31 "F.CrtYd" user "Package Geometry/Place Bound Top")
		(29 "B.CrtYd" user "Package Geometry/Place Bound Bottom")
		(35 "F.Fab" user "Ref Des/Assembly Top")
		(33 "B.Fab" user "Ref Des/Assembly Bottom")
	)
	(footprint ""
		(layer "F.Cu")
		(at 110.792768 -79.6036 180)
		(property "Reference" "C3D6"
			(at 0 0 180)
			(layer "F.SilkS")
			(hide yes)
			(effects
				(font
					(size 1.27 1.27)
				)
			)
		)
		(property "Value" ""
			(at 0 0 180)
			(layer "F.Fab")
			(effects
				(font
					(size 1.27 1.27)
				)
			)
		)
		(duplicate_pad_numbers_are_jumpers no)
		(fp_poly
			(pts
				(xy -0.4953 -0.2032) (xy 0.4953 -0.2032) (xy 0.4953 1.6002) (xy -0.4953 1.6002)
			)
			(stroke
				(width 0)
				(type default)
			)
			(fill no)
			(layer "F.CrtYd")
		)
		(fp_line
			(start 0.4953 1.6002)
			(end -0.4953 1.6002)
			(stroke
				(width 0.1)
				(type default)
			)
			(layer "F.Fab")
		)
		(fp_line
			(start 0.4953 -0.2032)
			(end 0.4953 1.6002)
			(stroke
				(width 0.1)
				(type default)
			)
			(layer "F.Fab")
		)
		(fp_line
			(start -0.4953 1.6002)
			(end -0.4953 -0.2032)
			(stroke
				(width 0.1)
				(type default)
			)
			(layer "F.Fab")
		)
		(fp_line
			(start -0.4953 -0.2032)
			(end 0.4953 -0.2032)
			(stroke
				(width 0.1)
				(type default)
			)
			(layer "F.Fab")
		)
		(pad "1" smd rect
			(at 0 0 180)
			(size 0.762 0.889)
			(layers "F.Cu" "F.Mask" "F.Paste")
			(net "PVCCMCP_CPU1")
		)
		(pad "2" smd rect
			(at 0 1.397 180)
			(size 0.762 0.889)
			(layers "F.Cu" "F.Mask" "F.Paste")
			(net "GND")
		)
		(zone
			(layer "F.Cu")
			(hatch none 0.5)
			(connect_pads
				(clearance 0)
			)
			(min_thickness 0.25)
			(keepout
				(tracks not_allowed)
				(vias allowed)
				(pads allowed)
				(copperpour not_allowed)
				(footprints allowed)
			)
			(placement
				(enabled no)
				(sheetname "")
			)
			(fill
				(thermal_gap 0.5)
				(thermal_bridge_width 0.5)
				(island_removal_mode 0)
			)
			(polygon
				(pts
					(xy 111.173768 -80.0481) (xy 110.411768 -80.0481) (xy 110.411768 -80.5561) (xy 111.173768 -80.5561)
				)
			)
		)
	)
	(footprint ""
		(layer "F.Cu")
		(at 485.4956 -50.2539 180)
		(property "Reference" "C9E4"
			(at 0 0 180)
			(layer "F.SilkS")
			(hide yes)
			(effects
				(font
					(size 1.27 1.27)
				)
			)
		)
		(property "Value" ""
			(at 0 0 180)
			(layer "F.Fab")
			(effects
				(font
					(size 1.27 1.27)
				)
			)
		)
		(duplicate_pad_numbers_are_jumpers no)
		(fp_poly
			(pts
				(xy 0.3048 -0.1016) (xy 0.3048 0.9906) (xy -0.3048 0.9906) (xy -0.3048 -0.1016)
			)
			(stroke
				(width 0)
				(type default)
			)
			(fill no)
			(layer "F.CrtYd")
		)
		(fp_line
			(start 0.3048 0.9906)
			(end 0.3048 -0.1016)
			(stroke
				(width 0.1)
				(type default)
			)
			(layer "F.Fab")
		)
		(fp_line
			(start 0.3048 -0.1016)
			(end -0.3048 -0.1016)
			(stroke
				(width 0.1)
				(type default)
			)
			(layer "F.Fab")
		)
		(fp_line
			(start -0.3048 0.9906)
			(end 0.3048 0.9906)
			(stroke
				(width 0.1)
				(type default)
			)
			(layer "F.Fab")
		)
		(fp_line
			(start -0.3048 -0.1016)
			(end -0.3048 0.9906)
			(stroke
				(width 0.1)
				(type default)
			)
			(layer "F.Fab")
		)
		(pad "1" smd rect
			(at 0 0 180)
			(size 0.508 0.508)
			(layers "F.Cu" "F.Mask" "F.Paste")
			(net "PE_PCH_SPRV_RX_DP")
		)
		(pad "2" smd rect
			(at 0 0.889 180)
			(size 0.508 0.508)
			(layers "F.Cu" "F.Mask" "F.Paste")
			(net "PE_PCH_SPRV_RX_C_DP")
		)
		(zone
			(layer "F.Cu")
			(hatch none 0.5)
			(connect_pads
				(clearance 0)
			)
			(min_thickness 0.25)
			(keepout
				(tracks not_allowed)
				(vias allowed)
				(pads allowed)
				(copperpour not_allowed)
				(footprints allowed)
			)
			(placement
				(enabled no)
				(sheetname "")
			)
			(fill
				(thermal_gap 0.5)
				(thermal_bridge_width 0.5)
				(island_removal_mode 0)
			)
			(polygon
				(pts
					(xy 485.7496 -50.8889) (xy 485.2416 -50.8889) (xy 485.2416 -50.5079) (xy 485.7496 -50.5079)
				)
			)
		)
		(zone
			(layer "F.Cu")
			(hatch none 0.5)
			(connect_pads
				(clearance 0)
			)
			(min_thickness 0.25)
			(keepout
				(tracks allowed)
				(vias not_allowed)
				(pads allowed)
				(copperpour not_allowed)
				(footprints allowed)
			)
			(placement
				(enabled no)
				(sheetname "")
			)
			(fill
				(thermal_gap 0.5)
				(thermal_bridge_width 0.5)
				(island_removal_mode 0)
			)
			(polygon
				(pts
					(xy 485.7496 -50.5079) (xy 485.2416 -50.5079) (xy 485.2416 -50.8889) (xy 485.7496 -50.8889)
				)
			)
		)
	)
	(footprint ""
		(layer "F.Cu")
		(at 431.7746 -44.2849 -90)
		(property "Reference" "R25W81"
			(at -0.8382 -0.67818 270)
			(unlocked yes)
			(layer "F.SilkS")
			(effects
				(font
					(size 0.4064 0.254)
					(thickness 0.1524)
				)
				(justify left)
			)
		)
		(property "Value" ""
			(at 0 0 270)
			(layer "F.Fab")
			(effects
				(font
					(size 1.27 1.27)
				)
			)
		)
		(duplicate_pad_numbers_are_jumpers no)
		(fp_poly
			(pts
				(xy -0.2794 -0.1016) (xy 0.2794 -0.1016) (xy 0.2794 0.9906) (xy -0.2794 0.9906)
			)
			(stroke
				(width 0)
				(type default)
			)
			(fill no)
			(layer "F.CrtYd")
		)
		(fp_line
			(start -0.2794 0.9906)
			(end 0.2794 0.9906)
			(stroke
				(width 0.1)
				(type default)
			)
			(layer "F.Fab")
		)
		(fp_line
			(start 0.2794 0.9906)
			(end 0.2794 -0.1016)
			(stroke
				(width 0.1)
				(type default)
			)
			(layer "F.Fab")
		)
		(fp_line
			(start -0.2794 -0.1016)
			(end -0.2794 0.9906)
			(stroke
				(width 0.1)
				(type default)
			)
			(layer "F.Fab")
		)
		(fp_line
			(start 0.2794 -0.1016)
			(end -0.2794 -0.1016)
			(stroke
				(width 0.1)
				(type default)
			)
			(layer "F.Fab")
		)
		(pad "1" smd rect
			(at 0 0 270)
			(size 0.508 0.508)
			(layers "F.Cu" "F.Mask" "F.Paste")
			(net "SPI_BMC_BT_CLK")
		)
		(pad "2" smd rect
			(at 0 0.889 270)
			(size 0.508 0.508)
			(layers "F.Cu" "F.Mask" "F.Paste")
			(net "SPI_BMC_BT_CLK_R")
		)
		(zone
			(layer "F.Cu")
			(hatch none 0.5)
			(connect_pads
				(clearance 0)
			)
			(min_thickness 0.25)
			(keepout
				(tracks not_allowed)
				(vias allowed)
				(pads allowed)
				(copperpour not_allowed)
				(footprints allowed)
			)
			(placement
				(enabled no)
				(sheetname "")
			)
			(fill
				(thermal_gap 0.5)
				(thermal_bridge_width 0.5)
				(island_removal_mode 0)
			)
			(polygon
				(pts
					(xy 431.1396 -44.5389) (xy 431.1396 -44.0309) (xy 431.5206 -44.0309) (xy 431.5206 -44.5389)
				)
			)
		)
		(zone
			(layer "F.Cu")
			(hatch none 0.5)
			(connect_pads
				(clearance 0)
			)
			(min_thickness 0.25)
			(keepout
				(tracks allowed)
				(vias not_allowed)
				(pads allowed)
				(copperpour not_allowed)
				(footprints allowed)
			)
			(placement
				(enabled no)
				(sheetname "")
			)
			(fill
				(thermal_gap 0.5)
				(thermal_bridge_width 0.5)
				(island_removal_mode 0)
			)
			(polygon
				(pts
					(xy 431.5206 -44.5389) (xy 431.5206 -44.0309) (xy 431.1396 -44.0309) (xy 431.1396 -44.5389)
				)
			)
		)
	)
	(footprint ""
		(layer "F.Cu")
		(at 171.196 -86.868 180)
		(property "Reference" "R4D6"
			(at 0 0 180)
			(layer "F.SilkS")
			(hide yes)
			(effects
				(font
					(size 1.27 1.27)
				)
			)
		)
		(property "Value" ""
			(at 0 0 180)
			(layer "F.Fab")
			(effects
				(font
					(size 1.27 1.27)
				)
			)
		)
		(duplicate_pad_numbers_are_jumpers no)
		(fp_poly
			(pts
				(xy -0.2794 -0.1016) (xy 0.2794 -0.1016) (xy 0.2794 0.9906) (xy -0.2794 0.9906)
			)
			(stroke
				(width 0)
				(type default)
			)
			(fill no)
			(layer "F.CrtYd")
		)
		(fp_line
			(start 0.2794 0.9906)
			(end 0.2794 -0.1016)
			(stroke
				(width 0.1)
				(type default)
			)
			(layer "F.Fab")
		)
		(fp_line
			(start 0.2794 -0.1016)
			(end -0.2794 -0.1016)
			(stroke
				(width 0.1)
				(type default)
			)
			(layer "F.Fab")
		)
		(fp_line
			(start -0.2794 0.9906)
			(end 0.2794 0.9906)
			(stroke
				(width 0.1)
				(type default)
			)
			(layer "F.Fab")
		)
		(fp_line
			(start -0.2794 -0.1016)
			(end -0.2794 0.9906)
			(stroke
				(width 0.1)
				(type default)
			)
			(layer "F.Fab")
		)
		(pad "1" smd rect
			(at 0 0 180)
			(size 0.508 0.508)
			(layers "F.Cu" "F.Mask" "F.Paste")
			(net "CLK_100M_CPU0_RC_REFCLK1_R_DP")
		)
		(pad "2" smd rect
			(at 0 0.889 180)
			(size 0.508 0.508)
			(layers "F.Cu" "F.Mask" "F.Paste")
			(net "CLK_100M_CPU0_RC_REFCLK1_DP")
		)
		(zone
			(layer "F.Cu")
			(hatch none 0.5)
			(connect_pads
				(clearance 0)
			)
			(min_thickness 0.25)
			(keepout
				(tracks not_allowed)
				(vias allowed)
				(pads allowed)
				(copperpour not_allowed)
				(footprints allowed)
			)
			(placement
				(enabled no)
				(sheetname "")
			)
			(fill
				(thermal_gap 0.5)
				(thermal_bridge_width 0.5)
				(island_removal_mode 0)
			)
			(polygon
				(pts
					(xy 171.45 -87.503) (xy 170.942 -87.503) (xy 170.942 -87.122) (xy 171.45 -87.122)
				)
			)
		)
		(zone
			(layer "F.Cu")
			(hatch none 0.5)
			(connect_pads
				(clearance 0)
			)
			(min_thickness 0.25)
			(keepout
				(tracks allowed)
				(vias not_allowed)
				(pads allowed)
				(copperpour not_allowed)
				(footprints allowed)
			)
			(placement
				(enabled no)
				(sheetname "")
			)
			(fill
				(thermal_gap 0.5)
				(thermal_bridge_width 0.5)
				(island_removal_mode 0)
			)
			(polygon
				(pts
					(xy 171.45 -87.122) (xy 170.942 -87.122) (xy 170.942 -87.503) (xy 171.45 -87.503)
				)
			)
		)
	)
	(footprint ""
		(layer "F.Cu")
		(at 418.7952 -92.6719 -90)
		(property "Reference" "C8C14"
			(at 0 0 270)
			(layer "F.SilkS")
			(hide yes)
			(effects
				(font
					(size 1.27 1.27)
				)
			)
		)
		(property "Value" ""
			(at 0 0 270)
			(layer "F.Fab")
			(effects
				(font
					(size 1.27 1.27)
				)
			)
		)
		(duplicate_pad_numbers_are_jumpers no)
		(fp_poly
			(pts
				(xy 0.3048 -0.1016) (xy 0.3048 0.9906) (xy -0.3048 0.9906) (xy -0.3048 -0.1016)
			)
			(stroke
				(width 0)
				(type default)
			)
			(fill no)
			(layer "F.CrtYd")
		)
		(fp_line
			(start -0.3048 0.9906)
			(end 0.3048 0.9906)
			(stroke
				(width 0.1)
				(type default)
			)
			(layer "F.Fab")
		)
		(fp_line
			(start 0.3048 0.9906)
			(end 0.3048 -0.1016)
			(stroke
				(width 0.1)
				(type default)
			)
			(layer "F.Fab")
		)
		(fp_line
			(start -0.3048 -0.1016)
			(end -0.3048 0.9906)
			(stroke
				(width 0.1)
				(type default)
			)
			(layer "F.Fab")
		)
		(fp_line
			(start 0.3048 -0.1016)
			(end -0.3048 -0.1016)
			(stroke
				(width 0.1)
				(type default)
			)
			(layer "F.Fab")
		)
		(pad "1" smd rect
			(at 0 0 270)
			(size 0.508 0.508)
			(layers "F.Cu" "F.Mask" "F.Paste")
			(net "KR_P0_OCP_RX_DN")
		)
		(pad "2" smd rect
			(at 0 0.889 270)
			(size 0.508 0.508)
			(layers "F.Cu" "F.Mask" "F.Paste")
			(net "KR_P0_OCP_RX_C_DN")
		)
		(zone
			(layer "F.Cu")
			(hatch none 0.5)
			(connect_pads
				(clearance 0)
			)
			(min_thickness 0.25)
			(keepout
				(tracks not_allowed)
				(vias allowed)
				(pads allowed)
				(copperpour not_allowed)
				(footprints allowed)
			)
			(placement
				(enabled no)
				(sheetname "")
			)
			(fill
				(thermal_gap 0.5)
				(thermal_bridge_width 0.5)
				(island_removal_mode 0)
			)
			(polygon
				(pts
					(xy 418.1602 -92.9259) (xy 418.1602 -92.4179) (xy 418.5412 -92.4179) (xy 418.5412 -92.9259)
				)
			)
		)
		(zone
			(layer "F.Cu")
			(hatch none 0.5)
			(connect_pads
				(clearance 0)
			)
			(min_thickness 0.25)
			(keepout
				(tracks allowed)
				(vias not_allowed)
				(pads allowed)
				(copperpour not_allowed)
				(footprints allowed)
			)
			(placement
				(enabled no)
				(sheetname "")
			)
			(fill
				(thermal_gap 0.5)
				(thermal_bridge_width 0.5)
				(island_removal_mode 0)
			)
			(polygon
				(pts
					(xy 418.5412 -92.9259) (xy 418.5412 -92.4179) (xy 418.1602 -92.4179) (xy 418.1602 -92.9259)
				)
			)
		)
	)
	(footprint ""
		(layer "F.Cu")
		(at 170.6245 -130.175 90)
		(property "Reference" "R4B9"
			(at 0 0 90)
			(layer "F.SilkS")
			(hide yes)
			(effects
				(font
					(size 1.27 1.27)
				)
			)
		)
		(property "Value" ""
			(at 0 0 90)
			(layer "F.Fab")
			(effects
				(font
					(size 1.27 1.27)
				)
			)
		)
		(duplicate_pad_numbers_are_jumpers no)
		(fp_poly
			(pts
				(xy -0.2794 -0.1016) (xy 0.2794 -0.1016) (xy 0.2794 0.9906) (xy -0.2794 0.9906)
			)
			(stroke
				(width 0)
				(type default)
			)
			(fill no)
			(layer "F.CrtYd")
		)
		(fp_line
			(start 0.2794 -0.1016)
			(end -0.2794 -0.1016)
			(stroke
				(width 0.1)
				(type default)
			)
			(layer "F.Fab")
		)
		(fp_line
			(start -0.2794 -0.1016)
			(end -0.2794 0.9906)
			(stroke
				(width 0.1)
				(type default)
			)
			(layer "F.Fab")
		)
		(fp_line
			(start 0.2794 0.9906)
			(end 0.2794 -0.1016)
			(stroke
				(width 0.1)
				(type default)
			)
			(layer "F.Fab")
		)
		(fp_line
			(start -0.2794 0.9906)
			(end 0.2794 0.9906)
			(stroke
				(width 0.1)
				(type default)
			)
			(layer "F.Fab")
		)
		(pad "1" smd rect
			(at 0 0 90)
			(size 0.508 0.508)
			(layers "F.Cu" "F.Mask" "F.Paste")
			(net "VSENSE_PVPP_KLM")
		)
		(pad "2" smd rect
			(at 0 0.889 90)
			(size 0.508 0.508)
			(layers "F.Cu" "F.Mask" "F.Paste")
			(net "VR_COMP_PVPP_KLM")
		)
		(zone
			(layer "F.Cu")
			(hatch none 0.5)
			(connect_pads
				(clearance 0)
			)
			(min_thickness 0.25)
			(keepout
				(tracks allowed)
				(vias not_allowed)
				(pads allowed)
				(copperpour not_allowed)
				(footprints allowed)
			)
			(placement
				(enabled no)
				(sheetname "")
			)
			(fill
				(thermal_gap 0.5)
				(thermal_bridge_width 0.5)
				(island_removal_mode 0)
			)
			(polygon
				(pts
					(xy 170.8785 -129.921) (xy 170.8785 -130.429) (xy 171.2595 -130.429) (xy 171.2595 -129.921)
				)
			)
		)
		(zone
			(layer "F.Cu")
			(hatch none 0.5)
			(connect_pads
				(clearance 0)
			)
			(min_thickness 0.25)
			(keepout
				(tracks not_allowed)
				(vias allowed)
				(pads allowed)
				(copperpour not_allowed)
				(footprints allowed)
			)
			(placement
				(enabled no)
				(sheetname "")
			)
			(fill
				(thermal_gap 0.5)
				(thermal_bridge_width 0.5)
				(island_removal_mode 0)
			)
			(polygon
				(pts
					(xy 171.2595 -129.921) (xy 171.2595 -130.429) (xy 170.8785 -130.429) (xy 170.8785 -129.921)
				)
			)
		)
	)
	(footprint ""
		(layer "F.Cu")
		(at 12.9286 -75.8952)
		(property "Reference" "R1D33"
			(at 0 0 0)
			(layer "F.SilkS")
			(hide yes)
			(effects
				(font
					(size 1.27 1.27)
				)
			)
		)
		(property "Value" ""
			(at 0 0 0)
			(layer "F.Fab")
			(effects
				(font
					(size 1.27 1.27)
				)
			)
		)
		(duplicate_pad_numbers_are_jumpers no)
		(fp_poly
			(pts
				(xy -0.2794 -0.1016) (xy 0.2794 -0.1016) (xy 0.2794 0.9906) (xy -0.2794 0.9906)
			)
			(stroke
				(width 0)
				(type default)
			)
			(fill no)
			(layer "F.CrtYd")
		)
		(fp_line
			(start -0.2794 -0.1016)
			(end -0.2794 0.9906)
			(stroke
				(width 0.1)
				(type default)
			)
			(layer "F.Fab")
		)
		(fp_line
			(start -0.2794 0.9906)
			(end 0.2794 0.9906)
			(stroke
				(width 0.1)
				(type default)
			)
			(layer "F.Fab")
		)
		(fp_line
			(start 0.2794 -0.1016)
			(end -0.2794 -0.1016)
			(stroke
				(width 0.1)
				(type default)
			)
			(layer "F.Fab")
		)
		(fp_line
			(start 0.2794 0.9906)
			(end 0.2794 -0.1016)
			(stroke
				(width 0.1)
				(type default)
			)
			(layer "F.Fab")
		)
		(pad "1" smd rect
			(at 0 0)
			(size 0.508 0.508)
			(layers "F.Cu" "F.Mask" "F.Paste")
			(net "PWRGD_P12V_R")
		)
		(pad "2" smd rect
			(at 0 0.889)
			(size 0.508 0.508)
			(layers "F.Cu" "F.Mask" "F.Paste")
			(net "PWRGD_P12V_HSC")
		)
		(zone
			(layer "F.Cu")
			(hatch none 0.5)
			(connect_pads
				(clearance 0)
			)
			(min_thickness 0.25)
			(keepout
				(tracks allowed)
				(vias not_allowed)
				(pads allowed)
				(copperpour not_allowed)
				(footprints allowed)
			)
			(placement
				(enabled no)
				(sheetname "")
			)
			(fill
				(thermal_gap 0.5)
				(thermal_bridge_width 0.5)
				(island_removal_mode 0)
			)
			(polygon
				(pts
					(xy 12.6746 -75.6412) (xy 13.1826 -75.6412) (xy 13.1826 -75.2602) (xy 12.6746 -75.2602)
				)
			)
		)
		(zone
			(layer "F.Cu")
			(hatch none 0.5)
			(connect_pads
				(clearance 0)
			)
			(min_thickness 0.25)
			(keepout
				(tracks not_allowed)
				(vias allowed)
				(pads allowed)
				(copperpour not_allowed)
				(footprints allowed)
			)
			(placement
				(enabled no)
				(sheetname "")
			)
			(fill
				(thermal_gap 0.5)
				(thermal_bridge_width 0.5)
				(island_removal_mode 0)
			)
			(polygon
				(pts
					(xy 12.6746 -75.2602) (xy 13.1826 -75.2602) (xy 13.1826 -75.6412) (xy 12.6746 -75.6412)
				)
			)
		)
	)
)
